# S9S_MB_2U (Grand Teton) — schematic netlist excerpt (pin names and nets, part order shuffled) for the footprints in the layout excerpt that follows; sources: Cadence DE-HDL packaged netlist, KiCad conversion of 03242023_DA0F0TMBIJ0_F0T_Motherboard_J_brd_V01_OCP.brd

PR2220  Q_RES  60.4K 1% CHIP  pkg 0402LF  page 300 : A = PVNN_MAIN_CPU1_MODE ; B = GND
R3098  Q_RES  130 1% CHIP  pkg 0402LF  page 254 : A = LED_PWRGD_PVCCIN_CPU1 ; B = P3V3_AUX

(kicad_pcb
	(version 20260206)
	(generator "pcbnew")
	(generator_version "10.0")
	(general
		(thickness 1.6)
		(legacy_teardrops no)
	)
	(paper "A4")
	(title_block
		(title "03242023_DA0F0TMBIJ0_F0T_Motherboard_J_brd_V01_OCP.brd")
		(comment 1 "Grand Teton / footprints 1014-1015 of 6105")
	)
	(layers
		(0 "F.Cu" signal "TOP")
		(4 "In1.Cu" signal "GND")
		(6 "In2.Cu" signal "IN1")
		(8 "In3.Cu" signal "GND1")
		(10 "In4.Cu" signal "IN2")
		(12 "In5.Cu" signal "GND2")
		(14 "In6.Cu" signal "IN3")
		(16 "In7.Cu" signal "GND3")
		(18 "In8.Cu" signal "VCC")
		(20 "In9.Cu" signal "VCC1")
		(22 "In10.Cu" signal "GND4")
		(24 "In11.Cu" signal "IN4")
		(26 "In12.Cu" signal "GND5")
		(28 "In13.Cu" signal "IN5")
		(30 "In14.Cu" signal "GND6")
		(32 "In15.Cu" signal "IN6")
		(34 "In16.Cu" signal "GND7")
		(2 "B.Cu" signal "BOTTOM")
		(9 "F.Adhes" user "F.Adhesive")
		(11 "B.Adhes" user "B.Adhesive")
		(13 "F.Paste" user "Package Geometry/Pastemask Top")
		(15 "B.Paste" user "Package Geometry/Pastemask Bottom")
		(5 "F.SilkS" user "Ref Des/Silkscreen Top")
		(7 "B.SilkS" user "Ref Des/Silkscreen Bottom")
		(1 "F.Mask" user "Board Geometry/Soldermask Top")
		(3 "B.Mask" user "Board Geometry/Soldermask Bottom")
		(17 "Dwgs.User" user "User.Drawings")
		(19 "Cmts.User" user "User.Comments")
		(21 "Eco1.User" user "User.Eco1")
		(23 "Eco2.User" user "User.Eco2")
		(25 "Edge.Cuts" user "Board Geometry/Outline")
		(27 "Margin" user)
		(31 "F.CrtYd" user "Package Geometry/Place Bound Top")
		(29 "B.CrtYd" user "Package Geometry/Place Bound Bottom")
		(35 "F.Fab" user "Ref Des/Assembly Top")
		(33 "B.Fab" user "Ref Des/Assembly Bottom")
	)
	(footprint ""
		(layer "F.Cu")
		(at 96.48444 -65.143634 -90)
		(property "Reference" "R3098"
			(at 0 0 270)
			(layer "F.SilkS")
			(hide yes)
			(effects
				(font
					(size 1.27 1.27)
				)
			)
		)
		(property "Value" ""
			(at 0 0 270)
			(layer "F.Fab")
			(effects
				(font
					(size 1.27 1.27)
				)
			)
		)
		(duplicate_pad_numbers_are_jumpers no)
		(fp_line
			(start -0.7874 0.4064)
			(end -0.7874 -0.4064)
			(stroke
				(width 0.1524)
				(type default)
			)
			(layer "F.SilkS")
		)
		(fp_line
			(start 0.7874 0.4064)
			(end -0.7874 0.4064)
			(stroke
				(width 0.1524)
				(type default)
			)
			(layer "F.SilkS")
		)
		(fp_line
			(start -0.7874 -0.4064)
			(end 0.7874 -0.4064)
			(stroke
				(width 0.1524)
				(type default)
			)
			(layer "F.SilkS")
		)
		(fp_line
			(start 0.7874 -0.4064)
			(end 0.7874 0.4064)
			(stroke
				(width 0.1524)
				(type default)
			)
			(layer "F.SilkS")
		)
		(fp_line
			(start -0.67945 0.3048)
			(end -0.67945 -0.305054)
			(stroke
				(width 0.1)
				(type default)
			)
			(layer "F.Fab")
		)
		(fp_line
			(start -0.12065 0.3048)
			(end -0.67945 0.3048)
			(stroke
				(width 0.1)
				(type default)
			)
			(layer "F.Fab")
		)
		(fp_line
			(start 0.120396 0.3048)
			(end 0.120396 0.2794)
			(stroke
				(width 0.1)
				(type default)
			)
			(layer "F.Fab")
		)
		(fp_line
			(start 0.67945 0.3048)
			(end 0.120396 0.3048)
			(stroke
				(width 0.1)
				(type default)
			)
			(layer "F.Fab")
		)
		(fp_line
			(start -0.12065 0.2794)
			(end -0.12065 0.3048)
			(stroke
				(width 0.1)
				(type default)
			)
			(layer "F.Fab")
		)
		(fp_line
			(start 0.120396 0.2794)
			(end -0.12065 0.2794)
			(stroke
				(width 0.1)
				(type default)
			)
			(layer "F.Fab")
		)
		(fp_line
			(start -0.12065 -0.2794)
			(end 0.12065 -0.2794)
			(stroke
				(width 0.1)
				(type default)
			)
			(layer "F.Fab")
		)
		(fp_line
			(start 0.12065 -0.2794)
			(end 0.12065 -0.3048)
			(stroke
				(width 0.1)
				(type default)
			)
			(layer "F.Fab")
		)
		(fp_line
			(start 0.12065 -0.3048)
			(end 0.67945 -0.3048)
			(stroke
				(width 0.1)
				(type default)
			)
			(layer "F.Fab")
		)
		(fp_line
			(start 0.67945 -0.3048)
			(end 0.67945 0.3048)
			(stroke
				(width 0.1)
				(type default)
			)
			(layer "F.Fab")
		)
		(fp_line
			(start -0.67945 -0.305054)
			(end -0.12065 -0.305054)
			(stroke
				(width 0.1)
				(type default)
			)
			(layer "F.Fab")
		)
		(fp_line
			(start -0.12065 -0.305054)
			(end -0.12065 -0.2794)
			(stroke
				(width 0.1)
				(type default)
			)
			(layer "F.Fab")
		)
		(pad "1" smd circle
			(at -0.40005 0 270)
			(size 0 0)
			(layers "F.Cu" "F.Mask" "F.Paste")
			(net "LED_PWRGD_PVCCIN_CPU1")
		)
		(pad "2" smd circle
			(at 0.40005 0 270)
			(size 0 0)
			(layers "F.Cu" "F.Mask" "F.Paste")
			(net "P3V3_AUX")
		)
	)
	(footprint ""
		(layer "F.Cu")
		(at 24.7015 -182.59552)
		(property "Reference" "PR2220"
			(at 0 0 0)
			(layer "F.SilkS")
			(hide yes)
			(effects
				(font
					(size 1.27 1.27)
				)
			)
		)
		(property "Value" ""
			(at 0 0 0)
			(layer "F.Fab")
			(effects
				(font
					(size 1.27 1.27)
				)
			)
		)
		(duplicate_pad_numbers_are_jumpers no)
		(fp_line
			(start -0.7874 -0.4064)
			(end 0.7874 -0.4064)
			(stroke
				(width 0.1524)
				(type default)
			)
			(layer "F.SilkS")
		)
		(fp_line
			(start -0.7874 0.4064)
			(end -0.7874 -0.4064)
			(stroke
				(width 0.1524)
				(type default)
			)
			(layer "F.SilkS")
		)
		(fp_line
			(start 0.7874 -0.4064)
			(end 0.7874 0.4064)
			(stroke
				(width 0.1524)
				(type default)
			)
			(layer "F.SilkS")
		)
		(fp_line
			(start 0.7874 0.4064)
			(end -0.7874 0.4064)
			(stroke
				(width 0.1524)
				(type default)
			)
			(layer "F.SilkS")
		)
		(fp_line
			(start -0.67945 -0.305054)
			(end -0.12065 -0.305054)
			(stroke
				(width 0.1)
				(type default)
			)
			(layer "F.Fab")
		)
		(fp_line
			(start -0.67945 0.3048)
			(end -0.67945 -0.305054)
			(stroke
				(width 0.1)
				(type default)
			)
			(layer "F.Fab")
		)
		(fp_line
			(start -0.12065 -0.305054)
			(end -0.12065 -0.2794)
			(stroke
				(width 0.1)
				(type default)
			)
			(layer "F.Fab")
		)
		(fp_line
			(start -0.12065 -0.2794)
			(end 0.12065 -0.2794)
			(stroke
				(width 0.1)
				(type default)
			)
			(layer "F.Fab")
		)
		(fp_line
			(start -0.12065 0.2794)
			(end -0.12065 0.3048)
			(stroke
				(width 0.1)
				(type default)
			)
			(layer "F.Fab")
		)
		(fp_line
			(start -0.12065 0.3048)
			(end -0.67945 0.3048)
			(stroke
				(width 0.1)
				(type default)
			)
			(layer "F.Fab")
		)
		(fp_line
			(start 0.120396 0.2794)
			(end -0.12065 0.2794)
			(stroke
				(width 0.1)
				(type default)
			)
			(layer "F.Fab")
		)
		(fp_line
			(start 0.120396 0.3048)
			(end 0.120396 0.2794)
			(stroke
				(width 0.1)
				(type default)
			)
			(layer "F.Fab")
		)
		(fp_line
			(start 0.12065 -0.3048)
			(end 0.67945 -0.3048)
			(stroke
				(width 0.1)
				(type default)
			)
			(layer "F.Fab")
		)
		(fp_line
			(start 0.12065 -0.2794)
			(end 0.12065 -0.3048)
			(stroke
				(width 0.1)
				(type default)
			)
			(layer "F.Fab")
		)
		(fp_line
			(start 0.67945 -0.3048)
			(end 0.67945 0.3048)
			(stroke
				(width 0.1)
				(type default)
			)
			(layer "F.Fab")
		)
		(fp_line
			(start 0.67945 0.3048)
			(end 0.120396 0.3048)
			(stroke
				(width 0.1)
				(type default)
			)
			(layer "F.Fab")
		)
		(pad "1" smd circle
			(at -0.40005 0)
			(size 0 0)
			(layers "F.Cu" "F.Mask" "F.Paste")
			(net "PVNN_MAIN_CPU1_MODE")
		)
		(pad "2" smd circle
			(at 0.40005 0)
			(size 0 0)
			(layers "F.Cu" "F.Mask" "F.Paste")
			(net "GND")
		)
	)
)
